(kicad_pcb
	(version 20260206)
	(generator "pcbnew")
	(generator_version "10.0")
	(general
		(thickness 1.6)
		(legacy_teardrops no)
	)
	(paper "A4")
	(title_block
		(title "04192023_DAF0TMB3IC0_F0TG_MB_C_brd_V02_OCP.brd")
		(comment 1 "Grand Teton / footprints 7451-7457 of 8354")
	)
	(layers
		(0 "F.Cu" signal "TOP")
		(4 "In1.Cu" signal "GND")
		(6 "In2.Cu" signal "IN1")
		(8 "In3.Cu" signal "GND1")
		(10 "In4.Cu" signal "IN2")
		(12 "In5.Cu" signal "GND2")
		(14 "In6.Cu" signal "IN3")
		(16 "In7.Cu" signal "GND3")
		(18 "In8.Cu" signal "VCC")
		(20 "In9.Cu" signal "VCC1")
		(22 "In10.Cu" signal "GND4")
		(24 "In11.Cu" signal "IN4")
		(26 "In12.Cu" signal "GND5")
		(28 "In13.Cu" signal "IN5")
		(30 "In14.Cu" signal "GND6")
		(32 "In15.Cu" signal "IN6")
		(34 "In16.Cu" signal "GND7")
		(2 "B.Cu" signal "BOTTOM")
		(9 "F.Adhes" user "F.Adhesive")
		(11 "B.Adhes" user "B.Adhesive")
		(13 "F.Paste" user "Package Geometry/Pastemask Top")
		(15 "B.Paste" user "Package Geometry/Pastemask Bottom")
		(5 "F.SilkS" user "Ref Des/Silkscreen Top")
		(7 "B.SilkS" user "Ref Des/Silkscreen Bottom")
		(1 "F.Mask" user "Board Geometry/Soldermask Top")
		(3 "B.Mask" user "Board Geometry/Soldermask Bottom")
		(17 "Dwgs.User" user "User.Drawings")
		(19 "Cmts.User" user "User.Comments")
		(21 "Eco1.User" user "User.Eco1")
		(23 "Eco2.User" user "User.Eco2")
		(25 "Edge.Cuts" user "Board Geometry/Outline")
		(27 "Margin" user)
		(31 "F.CrtYd" user "Package Geometry/Place Bound Top")
		(29 "B.CrtYd" user "Package Geometry/Place Bound Bottom")
		(35 "F.Fab" user "Ref Des/Assembly Top")
		(33 "B.Fab" user "Ref Des/Assembly Bottom")
	)
	(footprint ""
		(layer "B.Cu")
		(at 406.698958 -327.910952 180)
		(property "Reference" "R288"
			(at 0 0 0)
			(layer "B.SilkS")
			(hide yes)
			(effects
				(font
					(size 1.27 1.27)
				)
				(justify mirror)
			)
		)
		(property "Value" ""
			(at 0 0 0)
			(layer "B.Fab")
			(effects
				(font
					(size 1.27 1.27)
				)
				(justify mirror)
			)
		)
		(duplicate_pad_numbers_are_jumpers no)
		(fp_line
			(start 0.7874 0.4064)
			(end 0.7874 -0.4064)
			(stroke
				(width 0.1524)
				(type default)
			)
			(layer "B.SilkS")
		)
		(fp_line
			(start 0.7874 -0.4064)
			(end -0.7874 -0.4064)
			(stroke
				(width 0.1524)
				(type default)
			)
			(layer "B.SilkS")
		)
		(fp_line
			(start -0.7874 0.4064)
			(end 0.7874 0.4064)
			(stroke
				(width 0.1524)
				(type default)
			)
			(layer "B.SilkS")
		)
		(fp_line
			(start -0.7874 -0.4064)
			(end -0.7874 0.4064)
			(stroke
				(width 0.1524)
				(type default)
			)
			(layer "B.SilkS")
		)
		(fp_line
			(start 0.67945 0.3048)
			(end 0.67945 -0.305054)
			(stroke
				(width 0.1)
				(type default)
			)
			(layer "B.Fab")
		)
		(fp_line
			(start 0.67945 -0.305054)
			(end 0.12065 -0.305054)
			(stroke
				(width 0.1)
				(type default)
			)
			(layer "B.Fab")
		)
		(fp_line
			(start 0.12065 0.3048)
			(end 0.67945 0.3048)
			(stroke
				(width 0.1)
				(type default)
			)
			(layer "B.Fab")
		)
		(fp_line
			(start 0.12065 0.2794)
			(end 0.12065 0.3048)
			(stroke
				(width 0.1)
				(type default)
			)
			(layer "B.Fab")
		)
		(fp_line
			(start 0.12065 -0.2794)
			(end -0.12065 -0.2794)
			(stroke
				(width 0.1)
				(type default)
			)
			(layer "B.Fab")
		)
		(fp_line
			(start 0.12065 -0.305054)
			(end 0.12065 -0.2794)
			(stroke
				(width 0.1)
				(type default)
			)
			(layer "B.Fab")
		)
		(fp_line
			(start -0.120396 0.3048)
			(end -0.120396 0.2794)
			(stroke
				(width 0.1)
				(type default)
			)
			(layer "B.Fab")
		)
		(fp_line
			(start -0.120396 0.2794)
			(end 0.12065 0.2794)
			(stroke
				(width 0.1)
				(type default)
			)
			(layer "B.Fab")
		)
		(fp_line
			(start -0.12065 -0.2794)
			(end -0.12065 -0.3048)
			(stroke
				(width 0.1)
				(type default)
			)
			(layer "B.Fab")
		)
		(fp_line
			(start -0.12065 -0.3048)
			(end -0.67945 -0.3048)
			(stroke
				(width 0.1)
				(type default)
			)
			(layer "B.Fab")
		)
		(fp_line
			(start -0.67945 0.3048)
			(end -0.120396 0.3048)
			(stroke
				(width 0.1)
				(type default)
			)
			(layer "B.Fab")
		)
		(fp_line
			(start -0.67945 -0.3048)
			(end -0.67945 0.3048)
			(stroke
				(width 0.1)
				(type default)
			)
			(layer "B.Fab")
		)
		(pad "1" smd circle
			(at 0.40005 0)
			(size 0 0)
			(layers "B.Cu" "B.Mask" "B.Paste")
			(net "CPU0_PWR_GD_OUT")
		)
		(pad "2" smd circle
			(at -0.40005 0)
			(size 0 0)
			(layers "B.Cu" "B.Mask" "B.Paste")
			(net "PVDD18_S5_P0")
		)
	)
	(footprint ""
		(layer "B.Cu")
		(at 175.46701 -427.92269)
		(property "Reference" "R8111"
			(at 0 0 0)
			(layer "B.SilkS")
			(hide yes)
			(effects
				(font
					(size 1.27 1.27)
				)
				(justify mirror)
			)
		)
		(property "Value" ""
			(at 0 0 0)
			(layer "B.Fab")
			(effects
				(font
					(size 1.27 1.27)
				)
				(justify mirror)
			)
		)
		(duplicate_pad_numbers_are_jumpers no)
		(fp_line
			(start -0.7874 -0.4064)
			(end -0.7874 0.4064)
			(stroke
				(width 0.1524)
				(type default)
			)
			(layer "B.SilkS")
		)
		(fp_line
			(start -0.7874 0.4064)
			(end 0.7874 0.4064)
			(stroke
				(width 0.1524)
				(type default)
			)
			(layer "B.SilkS")
		)
		(fp_line
			(start 0.7874 -0.4064)
			(end -0.7874 -0.4064)
			(stroke
				(width 0.1524)
				(type default)
			)
			(layer "B.SilkS")
		)
		(fp_line
			(start 0.7874 0.4064)
			(end 0.7874 -0.4064)
			(stroke
				(width 0.1524)
				(type default)
			)
			(layer "B.SilkS")
		)
		(fp_line
			(start -0.67945 -0.3048)
			(end -0.67945 0.3048)
			(stroke
				(width 0.1)
				(type default)
			)
			(layer "B.Fab")
		)
		(fp_line
			(start -0.67945 0.3048)
			(end -0.120396 0.3048)
			(stroke
				(width 0.1)
				(type default)
			)
			(layer "B.Fab")
		)
		(fp_line
			(start -0.12065 -0.3048)
			(end -0.67945 -0.3048)
			(stroke
				(width 0.1)
				(type default)
			)
			(layer "B.Fab")
		)
		(fp_line
			(start -0.12065 -0.2794)
			(end -0.12065 -0.3048)
			(stroke
				(width 0.1)
				(type default)
			)
			(layer "B.Fab")
		)
		(fp_line
			(start -0.120396 0.2794)
			(end 0.12065 0.2794)
			(stroke
				(width 0.1)
				(type default)
			)
			(layer "B.Fab")
		)
		(fp_line
			(start -0.120396 0.3048)
			(end -0.120396 0.2794)
			(stroke
				(width 0.1)
				(type default)
			)
			(layer "B.Fab")
		)
		(fp_line
			(start 0.12065 -0.305054)
			(end 0.12065 -0.2794)
			(stroke
				(width 0.1)
				(type default)
			)
			(layer "B.Fab")
		)
		(fp_line
			(start 0.12065 -0.2794)
			(end -0.12065 -0.2794)
			(stroke
				(width 0.1)
				(type default)
			)
			(layer "B.Fab")
		)
		(fp_line
			(start 0.12065 0.2794)
			(end 0.12065 0.3048)
			(stroke
				(width 0.1)
				(type default)
			)
			(layer "B.Fab")
		)
		(fp_line
			(start 0.12065 0.3048)
			(end 0.67945 0.3048)
			(stroke
				(width 0.1)
				(type default)
			)
			(layer "B.Fab")
		)
		(fp_line
			(start 0.67945 -0.305054)
			(end 0.12065 -0.305054)
			(stroke
				(width 0.1)
				(type default)
			)
			(layer "B.Fab")
		)
		(fp_line
			(start 0.67945 0.3048)
			(end 0.67945 -0.305054)
			(stroke
				(width 0.1)
				(type default)
			)
			(layer "B.Fab")
		)
		(pad "1" smd circle
			(at 0.40005 0 180)
			(size 0 0)
			(layers "B.Cu" "B.Mask" "B.Paste")
			(net "P3V3_AUX")
		)
		(pad "2" smd circle
			(at -0.40005 0 180)
			(size 0 0)
			(layers "B.Cu" "B.Mask" "B.Paste")
			(net "A_HSC_LOW_GATE")
		)
	)
	(footprint ""
		(layer "B.Cu")
		(at 108.50626 -35.088068 90)
		(property "Reference" "C6109"
			(at 0 0 90)
			(layer "B.SilkS")
			(hide yes)
			(effects
				(font
					(size 1.27 1.27)
				)
				(justify mirror)
			)
		)
		(property "Value" ""
			(at 0 0 90)
			(layer "B.Fab")
			(effects
				(font
					(size 1.27 1.27)
				)
				(justify mirror)
			)
		)
		(duplicate_pad_numbers_are_jumpers no)
		(fp_line
			(start 0.7874 -0.4064)
			(end -0.7874 -0.4064)
			(stroke
				(width 0.1524)
				(type default)
			)
			(layer "B.SilkS")
		)
		(fp_line
			(start -0.7874 -0.4064)
			(end -0.7874 0.4064)
			(stroke
				(width 0.1524)
				(type default)
			)
			(layer "B.SilkS")
		)
		(fp_line
			(start 0.7874 0.4064)
			(end 0.7874 -0.4064)
			(stroke
				(width 0.1524)
				(type default)
			)
			(layer "B.SilkS")
		)
		(fp_line
			(start -0.7874 0.4064)
			(end 0.7874 0.4064)
			(stroke
				(width 0.1524)
				(type default)
			)
			(layer "B.SilkS")
		)
		(fp_line
			(start 0.67945 -0.305054)
			(end 0.12065 -0.305054)
			(stroke
				(width 0.1)
				(type default)
			)
			(layer "B.Fab")
		)
		(fp_line
			(start 0.12065 -0.305054)
			(end 0.12065 -0.2794)
			(stroke
				(width 0.1)
				(type default)
			)
			(layer "B.Fab")
		)
		(fp_line
			(start -0.12065 -0.3048)
			(end -0.67945 -0.3048)
			(stroke
				(width 0.1)
				(type default)
			)
			(layer "B.Fab")
		)
		(fp_line
			(start -0.67945 -0.3048)
			(end -0.67945 0.3048)
			(stroke
				(width 0.1)
				(type default)
			)
			(layer "B.Fab")
		)
		(fp_line
			(start 0.12065 -0.2794)
			(end -0.12065 -0.2794)
			(stroke
				(width 0.1)
				(type default)
			)
			(layer "B.Fab")
		)
		(fp_line
			(start -0.12065 -0.2794)
			(end -0.12065 -0.3048)
			(stroke
				(width 0.1)
				(type default)
			)
			(layer "B.Fab")
		)
		(fp_line
			(start 0.12065 0.2794)
			(end 0.12065 0.3048)
			(stroke
				(width 0.1)
				(type default)
			)
			(layer "B.Fab")
		)
		(fp_line
			(start -0.120396 0.2794)
			(end 0.12065 0.2794)
			(stroke
				(width 0.1)
				(type default)
			)
			(layer "B.Fab")
		)
		(fp_line
			(start 0.67945 0.3048)
			(end 0.67945 -0.305054)
			(stroke
				(width 0.1)
				(type default)
			)
			(layer "B.Fab")
		)
		(fp_line
			(start 0.12065 0.3048)
			(end 0.67945 0.3048)
			(stroke
				(width 0.1)
				(type default)
			)
			(layer "B.Fab")
		)
		(fp_line
			(start -0.120396 0.3048)
			(end -0.120396 0.2794)
			(stroke
				(width 0.1)
				(type default)
			)
			(layer "B.Fab")
		)
		(fp_line
			(start -0.67945 0.3048)
			(end -0.120396 0.3048)
			(stroke
				(width 0.1)
				(type default)
			)
			(layer "B.Fab")
		)
		(pad "1" smd circle
			(at 0.40005 0 270)
			(size 0 0)
			(layers "B.Cu" "B.Mask" "B.Paste")
			(net "P1V2_CPU0_USB2_DVDD12")
		)
		(pad "2" smd circle
			(at -0.40005 0 270)
			(size 0 0)
			(layers "B.Cu" "B.Mask" "B.Paste")
			(net "GND")
		)
	)
	(footprint ""
		(layer "B.Cu")
		(at 145.046192 -387.05028)
		(property "Reference" "C384"
			(at 0 0 0)
			(layer "B.SilkS")
			(hide yes)
			(effects
				(font
					(size 1.27 1.27)
				)
				(justify mirror)
			)
		)
		(property "Value" ""
			(at 0 0 0)
			(layer "B.Fab")
			(effects
				(font
					(size 1.27 1.27)
				)
				(justify mirror)
			)
		)
		(duplicate_pad_numbers_are_jumpers no)
		(fp_line
			(start -0.299974 -0.150114)
			(end -0.299974 0.150114)
			(stroke
				(width 0.1)
				(type default)
			)
			(layer "B.Fab")
		)
		(fp_line
			(start -0.299974 0.150114)
			(end 0.299974 0.150114)
			(stroke
				(width 0.1)
				(type default)
			)
			(layer "B.Fab")
		)
		(fp_line
			(start 0.299974 -0.150114)
			(end -0.299974 -0.150114)
			(stroke
				(width 0.1)
				(type default)
			)
			(layer "B.Fab")
		)
		(fp_line
			(start 0.299974 0.150114)
			(end 0.299974 -0.150114)
			(stroke
				(width 0.1)
				(type default)
			)
			(layer "B.Fab")
		)
		(pad "1" smd rect
			(at 0.2667 0 180)
			(size 0.3048 0.381)
			(layers "B.Cu" "B.Mask" "B.Paste")
			(net "P0V9_CPU1_RT2_2A")
		)
		(pad "2" smd rect
			(at -0.2667 0 180)
			(size 0.3048 0.381)
			(layers "B.Cu" "B.Mask" "B.Paste")
			(net "GND")
		)
	)
	(footprint ""
		(layer "B.Cu")
		(at 108.145834 -250.257564)
		(property "Reference" "C2301"
			(at 0 0 0)
			(layer "B.SilkS")
			(hide yes)
			(effects
				(font
					(size 1.27 1.27)
				)
				(justify mirror)
			)
		)
		(property "Value" ""
			(at 0 0 0)
			(layer "B.Fab")
			(effects
				(font
					(size 1.27 1.27)
				)
				(justify mirror)
			)
		)
		(duplicate_pad_numbers_are_jumpers no)
		(fp_line
			(start -0.7874 -0.4064)
			(end -0.7874 0.4064)
			(stroke
				(width 0.1524)
				(type default)
			)
			(layer "B.SilkS")
		)
		(fp_line
			(start -0.7874 0.4064)
			(end 0.7874 0.4064)
			(stroke
				(width 0.1524)
				(type default)
			)
			(layer "B.SilkS")
		)
		(fp_line
			(start 0.7874 -0.4064)
			(end -0.7874 -0.4064)
			(stroke
				(width 0.1524)
				(type default)
			)
			(layer "B.SilkS")
		)
		(fp_line
			(start 0.7874 0.4064)
			(end 0.7874 -0.4064)
			(stroke
				(width 0.1524)
				(type default)
			)
			(layer "B.SilkS")
		)
		(fp_line
			(start -0.67945 -0.3048)
			(end -0.67945 0.3048)
			(stroke
				(width 0.1)
				(type default)
			)
			(layer "B.Fab")
		)
		(fp_line
			(start -0.67945 0.3048)
			(end -0.120396 0.3048)
			(stroke
				(width 0.1)
				(type default)
			)
			(layer "B.Fab")
		)
		(fp_line
			(start -0.12065 -0.3048)
			(end -0.67945 -0.3048)
			(stroke
				(width 0.1)
				(type default)
			)
			(layer "B.Fab")
		)
		(fp_line
			(start -0.12065 -0.2794)
			(end -0.12065 -0.3048)
			(stroke
				(width 0.1)
				(type default)
			)
			(layer "B.Fab")
		)
		(fp_line
			(start -0.120396 0.2794)
			(end 0.12065 0.2794)
			(stroke
				(width 0.1)
				(type default)
			)
			(layer "B.Fab")
		)
		(fp_line
			(start -0.120396 0.3048)
			(end -0.120396 0.2794)
			(stroke
				(width 0.1)
				(type default)
			)
			(layer "B.Fab")
		)
		(fp_line
			(start 0.12065 -0.305054)
			(end 0.12065 -0.2794)
			(stroke
				(width 0.1)
				(type default)
			)
			(layer "B.Fab")
		)
		(fp_line
			(start 0.12065 -0.2794)
			(end -0.12065 -0.2794)
			(stroke
				(width 0.1)
				(type default)
			)
			(layer "B.Fab")
		)
		(fp_line
			(start 0.12065 0.2794)
			(end 0.12065 0.3048)
			(stroke
				(width 0.1)
				(type default)
			)
			(layer "B.Fab")
		)
		(fp_line
			(start 0.12065 0.3048)
			(end 0.67945 0.3048)
			(stroke
				(width 0.1)
				(type default)
			)
			(layer "B.Fab")
		)
		(fp_line
			(start 0.67945 -0.305054)
			(end 0.12065 -0.305054)
			(stroke
				(width 0.1)
				(type default)
			)
			(layer "B.Fab")
		)
		(fp_line
			(start 0.67945 0.3048)
			(end 0.67945 -0.305054)
			(stroke
				(width 0.1)
				(type default)
			)
			(layer "B.Fab")
		)
		(pad "1" smd circle
			(at 0.40005 0 180)
			(size 0 0)
			(layers "B.Cu" "B.Mask" "B.Paste")
			(net "PVDDCR_CPU0_P1")
		)
		(pad "2" smd circle
			(at -0.40005 0 180)
			(size 0 0)
			(layers "B.Cu" "B.Mask" "B.Paste")
			(net "GND")
		)
	)
	(footprint ""
		(layer "B.Cu")
		(at 202.903836 -193.99631)
		(property "Reference" "R115"
			(at 0 0 0)
			(layer "B.SilkS")
			(hide yes)
			(effects
				(font
					(size 1.27 1.27)
				)
				(justify mirror)
			)
		)
		(property "Value" ""
			(at 0 0 0)
			(layer "B.Fab")
			(effects
				(font
					(size 1.27 1.27)
				)
				(justify mirror)
			)
		)
		(duplicate_pad_numbers_are_jumpers no)
		(fp_line
			(start -0.7874 -0.4064)
			(end -0.7874 0.4064)
			(stroke
				(width 0.1524)
				(type default)
			)
			(layer "B.SilkS")
		)
		(fp_line
			(start -0.7874 0.4064)
			(end 0.7874 0.4064)
			(stroke
				(width 0.1524)
				(type default)
			)
			(layer "B.SilkS")
		)
		(fp_line
			(start 0.7874 -0.4064)
			(end -0.7874 -0.4064)
			(stroke
				(width 0.1524)
				(type default)
			)
			(layer "B.SilkS")
		)
		(fp_line
			(start 0.7874 0.4064)
			(end 0.7874 -0.4064)
			(stroke
				(width 0.1524)
				(type default)
			)
			(layer "B.SilkS")
		)
		(fp_line
			(start -0.67945 -0.3048)
			(end -0.67945 0.3048)
			(stroke
				(width 0.1)
				(type default)
			)
			(layer "B.Fab")
		)
		(fp_line
			(start -0.67945 0.3048)
			(end -0.120396 0.3048)
			(stroke
				(width 0.1)
				(type default)
			)
			(layer "B.Fab")
		)
		(fp_line
			(start -0.12065 -0.3048)
			(end -0.67945 -0.3048)
			(stroke
				(width 0.1)
				(type default)
			)
			(layer "B.Fab")
		)
		(fp_line
			(start -0.12065 -0.2794)
			(end -0.12065 -0.3048)
			(stroke
				(width 0.1)
				(type default)
			)
			(layer "B.Fab")
		)
		(fp_line
			(start -0.120396 0.2794)
			(end 0.12065 0.2794)
			(stroke
				(width 0.1)
				(type default)
			)
			(layer "B.Fab")
		)
		(fp_line
			(start -0.120396 0.3048)
			(end -0.120396 0.2794)
			(stroke
				(width 0.1)
				(type default)
			)
			(layer "B.Fab")
		)
		(fp_line
			(start 0.12065 -0.305054)
			(end 0.12065 -0.2794)
			(stroke
				(width 0.1)
				(type default)
			)
			(layer "B.Fab")
		)
		(fp_line
			(start 0.12065 -0.2794)
			(end -0.12065 -0.2794)
			(stroke
				(width 0.1)
				(type default)
			)
			(layer "B.Fab")
		)
		(fp_line
			(start 0.12065 0.2794)
			(end 0.12065 0.3048)
			(stroke
				(width 0.1)
				(type default)
			)
			(layer "B.Fab")
		)
		(fp_line
			(start 0.12065 0.3048)
			(end 0.67945 0.3048)
			(stroke
				(width 0.1)
				(type default)
			)
			(layer "B.Fab")
		)
		(fp_line
			(start 0.67945 -0.305054)
			(end 0.12065 -0.305054)
			(stroke
				(width 0.1)
				(type default)
			)
			(layer "B.Fab")
		)
		(fp_line
			(start 0.67945 0.3048)
			(end 0.67945 -0.305054)
			(stroke
				(width 0.1)
				(type default)
			)
			(layer "B.Fab")
		)
		(pad "1" smd circle
			(at 0.40005 0 180)
			(size 0 0)
			(layers "B.Cu" "B.Mask" "B.Paste")
			(net "P3V3")
		)
		(pad "2" smd circle
			(at -0.40005 0 180)
			(size 0 0)
			(layers "B.Cu" "B.Mask" "B.Paste")
			(net "PWRGD_CHL_CPU1_DIMM")
		)
	)
	(footprint ""
		(layer "B.Cu")
		(at 96.84639 -388.011162 -90)
		(property "Reference" "C340"
			(at 0 0 90)
			(layer "B.SilkS")
			(hide yes)
			(effects
				(font
					(size 1.27 1.27)
				)
				(justify mirror)
			)
		)
		(property "Value" ""
			(at 0 0 90)
			(layer "B.Fab")
			(effects
				(font
					(size 1.27 1.27)
				)
				(justify mirror)
			)
		)
		(duplicate_pad_numbers_are_jumpers no)
		(fp_line
			(start -0.299974 0.150114)
			(end 0.299974 0.150114)
			(stroke
				(width 0.1)
				(type default)
			)
			(layer "B.Fab")
		)
		(fp_line
			(start 0.299974 0.150114)
			(end 0.299974 -0.150114)
			(stroke
				(width 0.1)
				(type default)
			)
			(layer "B.Fab")
		)
		(fp_line
			(start -0.299974 -0.150114)
			(end -0.299974 0.150114)
			(stroke
				(width 0.1)
				(type default)
			)
			(layer "B.Fab")
		)
		(fp_line
			(start 0.299974 -0.150114)
			(end -0.299974 -0.150114)
			(stroke
				(width 0.1)
				(type default)
			)
			(layer "B.Fab")
		)
		(pad "1" smd rect
			(at 0.2667 0 90)
			(size 0.3048 0.381)
			(layers "B.Cu" "B.Mask" "B.Paste")
			(net "P0V9_CPU1_RT1_2A")
		)
		(pad "2" smd rect
			(at -0.2667 0 90)
			(size 0.3048 0.381)
			(layers "B.Cu" "B.Mask" "B.Paste")
			(net "GND")
		)
	)
)
